# S9S_MB_2U (Grand Teton) — schematic netlist excerpt (pin names and nets, part order shuffled) for the footprints in the layout excerpt that follows; sources: Cadence DE-HDL packaged netlist, KiCad conversion of 03242023_DA0F0TMBIJ0_F0T_Motherboard_J_brd_V01_OCP.brd

R536  Q_RES  10K 1% EMPTY  pkg 0402LF  page 231 : A = P3V3_AUX ; B = PCA9548_PCIE3_ADDR2
R2914  Q_RES  4.7K 5% EMPTY  pkg 0402LF  page 149 : A = P3V3_AUX ; B = FM_SWB_PWR_EN_R1_BUF

(kicad_pcb
	(version 20260206)
	(generator "pcbnew")
	(generator_version "10.0")
	(general
		(thickness 1.6)
		(legacy_teardrops no)
	)
	(paper "A4")
	(title_block
		(title "03242023_DA0F0TMBIJ0_F0T_Motherboard_J_brd_V01_OCP.brd")
		(comment 1 "Grand Teton / footprints 3004-3005 of 6105")
	)
	(layers
		(0 "F.Cu" signal "TOP")
		(4 "In1.Cu" signal "GND")
		(6 "In2.Cu" signal "IN1")
		(8 "In3.Cu" signal "GND1")
		(10 "In4.Cu" signal "IN2")
		(12 "In5.Cu" signal "GND2")
		(14 "In6.Cu" signal "IN3")
		(16 "In7.Cu" signal "GND3")
		(18 "In8.Cu" signal "VCC")
		(20 "In9.Cu" signal "VCC1")
		(22 "In10.Cu" signal "GND4")
		(24 "In11.Cu" signal "IN4")
		(26 "In12.Cu" signal "GND5")
		(28 "In13.Cu" signal "IN5")
		(30 "In14.Cu" signal "GND6")
		(32 "In15.Cu" signal "IN6")
		(34 "In16.Cu" signal "GND7")
		(2 "B.Cu" signal "BOTTOM")
		(9 "F.Adhes" user "F.Adhesive")
		(11 "B.Adhes" user "B.Adhesive")
		(13 "F.Paste" user "Package Geometry/Pastemask Top")
		(15 "B.Paste" user "Package Geometry/Pastemask Bottom")
		(5 "F.SilkS" user "Ref Des/Silkscreen Top")
		(7 "B.SilkS" user "Ref Des/Silkscreen Bottom")
		(1 "F.Mask" user "Board Geometry/Soldermask Top")
		(3 "B.Mask" user "Board Geometry/Soldermask Bottom")
		(17 "Dwgs.User" user "User.Drawings")
		(19 "Cmts.User" user "User.Comments")
		(21 "Eco1.User" user "User.Eco1")
		(23 "Eco2.User" user "User.Eco2")
		(25 "Edge.Cuts" user "Board Geometry/Outline")
		(27 "Margin" user)
		(31 "F.CrtYd" user "Package Geometry/Place Bound Top")
		(29 "B.CrtYd" user "Package Geometry/Place Bound Bottom")
		(35 "F.Fab" user "Ref Des/Assembly Top")
		(33 "B.Fab" user "Ref Des/Assembly Bottom")
	)
	(footprint ""
		(layer "F.Cu")
		(at 131.466844 -137.114026 180)
		(property "Reference" "R536"
			(at 0 0 180)
			(layer "F.SilkS")
			(hide yes)
			(effects
				(font
					(size 1.27 1.27)
				)
			)
		)
		(property "Value" ""
			(at 0 0 180)
			(layer "F.Fab")
			(effects
				(font
					(size 1.27 1.27)
				)
			)
		)
		(duplicate_pad_numbers_are_jumpers no)
		(fp_line
			(start 0.7874 0.4064)
			(end -0.7874 0.4064)
			(stroke
				(width 0.1524)
				(type default)
			)
			(layer "F.SilkS")
		)
		(fp_line
			(start 0.7874 -0.4064)
			(end 0.7874 0.4064)
			(stroke
				(width 0.1524)
				(type default)
			)
			(layer "F.SilkS")
		)
		(fp_line
			(start -0.7874 0.4064)
			(end -0.7874 -0.4064)
			(stroke
				(width 0.1524)
				(type default)
			)
			(layer "F.SilkS")
		)
		(fp_line
			(start -0.7874 -0.4064)
			(end 0.7874 -0.4064)
			(stroke
				(width 0.1524)
				(type default)
			)
			(layer "F.SilkS")
		)
		(fp_line
			(start 0.67945 0.3048)
			(end 0.120396 0.3048)
			(stroke
				(width 0.1)
				(type default)
			)
			(layer "F.Fab")
		)
		(fp_line
			(start 0.67945 -0.3048)
			(end 0.67945 0.3048)
			(stroke
				(width 0.1)
				(type default)
			)
			(layer "F.Fab")
		)
		(fp_line
			(start 0.12065 -0.2794)
			(end 0.12065 -0.3048)
			(stroke
				(width 0.1)
				(type default)
			)
			(layer "F.Fab")
		)
		(fp_line
			(start 0.12065 -0.3048)
			(end 0.67945 -0.3048)
			(stroke
				(width 0.1)
				(type default)
			)
			(layer "F.Fab")
		)
		(fp_line
			(start 0.120396 0.3048)
			(end 0.120396 0.2794)
			(stroke
				(width 0.1)
				(type default)
			)
			(layer "F.Fab")
		)
		(fp_line
			(start 0.120396 0.2794)
			(end -0.12065 0.2794)
			(stroke
				(width 0.1)
				(type default)
			)
			(layer "F.Fab")
		)
		(fp_line
			(start -0.12065 0.3048)
			(end -0.67945 0.3048)
			(stroke
				(width 0.1)
				(type default)
			)
			(layer "F.Fab")
		)
		(fp_line
			(start -0.12065 0.2794)
			(end -0.12065 0.3048)
			(stroke
				(width 0.1)
				(type default)
			)
			(layer "F.Fab")
		)
		(fp_line
			(start -0.12065 -0.2794)
			(end 0.12065 -0.2794)
			(stroke
				(width 0.1)
				(type default)
			)
			(layer "F.Fab")
		)
		(fp_line
			(start -0.12065 -0.305054)
			(end -0.12065 -0.2794)
			(stroke
				(width 0.1)
				(type default)
			)
			(layer "F.Fab")
		)
		(fp_line
			(start -0.67945 0.3048)
			(end -0.67945 -0.305054)
			(stroke
				(width 0.1)
				(type default)
			)
			(layer "F.Fab")
		)
		(fp_line
			(start -0.67945 -0.305054)
			(end -0.12065 -0.305054)
			(stroke
				(width 0.1)
				(type default)
			)
			(layer "F.Fab")
		)
		(pad "1" smd circle
			(at -0.40005 0 180)
			(size 0 0)
			(layers "F.Cu" "F.Mask" "F.Paste")
			(net "P3V3_AUX")
		)
		(pad "2" smd circle
			(at 0.40005 0 180)
			(size 0 0)
			(layers "F.Cu" "F.Mask" "F.Paste")
			(net "PCA9548_PCIE3_ADDR2")
		)
	)
	(footprint ""
		(layer "F.Cu")
		(at 31.29788 -430.875948 180)
		(property "Reference" "R2914"
			(at 0 0 180)
			(layer "F.SilkS")
			(hide yes)
			(effects
				(font
					(size 1.27 1.27)
				)
			)
		)
		(property "Value" ""
			(at 0 0 180)
			(layer "F.Fab")
			(effects
				(font
					(size 1.27 1.27)
				)
			)
		)
		(duplicate_pad_numbers_are_jumpers no)
		(fp_line
			(start 0.7874 0.4064)
			(end -0.7874 0.4064)
			(stroke
				(width 0.1524)
				(type default)
			)
			(layer "F.SilkS")
		)
		(fp_line
			(start 0.7874 -0.4064)
			(end 0.7874 0.4064)
			(stroke
				(width 0.1524)
				(type default)
			)
			(layer "F.SilkS")
		)
		(fp_line
			(start -0.7874 0.4064)
			(end -0.7874 -0.4064)
			(stroke
				(width 0.1524)
				(type default)
			)
			(layer "F.SilkS")
		)
		(fp_line
			(start -0.7874 -0.4064)
			(end 0.7874 -0.4064)
			(stroke
				(width 0.1524)
				(type default)
			)
			(layer "F.SilkS")
		)
		(fp_line
			(start 0.67945 0.3048)
			(end 0.120396 0.3048)
			(stroke
				(width 0.1)
				(type default)
			)
			(layer "F.Fab")
		)
		(fp_line
			(start 0.67945 -0.3048)
			(end 0.67945 0.3048)
			(stroke
				(width 0.1)
				(type default)
			)
			(layer "F.Fab")
		)
		(fp_line
			(start 0.12065 -0.2794)
			(end 0.12065 -0.3048)
			(stroke
				(width 0.1)
				(type default)
			)
			(layer "F.Fab")
		)
		(fp_line
			(start 0.12065 -0.3048)
			(end 0.67945 -0.3048)
			(stroke
				(width 0.1)
				(type default)
			)
			(layer "F.Fab")
		)
		(fp_line
			(start 0.120396 0.3048)
			(end 0.120396 0.2794)
			(stroke
				(width 0.1)
				(type default)
			)
			(layer "F.Fab")
		)
		(fp_line
			(start 0.120396 0.2794)
			(end -0.12065 0.2794)
			(stroke
				(width 0.1)
				(type default)
			)
			(layer "F.Fab")
		)
		(fp_line
			(start -0.12065 0.3048)
			(end -0.67945 0.3048)
			(stroke
				(width 0.1)
				(type default)
			)
			(layer "F.Fab")
		)
		(fp_line
			(start -0.12065 0.2794)
			(end -0.12065 0.3048)
			(stroke
				(width 0.1)
				(type default)
			)
			(layer "F.Fab")
		)
		(fp_line
			(start -0.12065 -0.2794)
			(end 0.12065 -0.2794)
			(stroke
				(width 0.1)
				(type default)
			)
			(layer "F.Fab")
		)
		(fp_line
			(start -0.12065 -0.305054)
			(end -0.12065 -0.2794)
			(stroke
				(width 0.1)
				(type default)
			)
			(layer "F.Fab")
		)
		(fp_line
			(start -0.67945 0.3048)
			(end -0.67945 -0.305054)
			(stroke
				(width 0.1)
				(type default)
			)
			(layer "F.Fab")
		)
		(fp_line
			(start -0.67945 -0.305054)
			(end -0.12065 -0.305054)
			(stroke
				(width 0.1)
				(type default)
			)
			(layer "F.Fab")
		)
		(pad "1" smd circle
			(at -0.40005 0 180)
			(size 0 0)
			(layers "F.Cu" "F.Mask" "F.Paste")
			(net "P3V3_AUX")
		)
		(pad "2" smd circle
			(at 0.40005 0 180)
			(size 0 0)
			(layers "F.Cu" "F.Mask" "F.Paste")
			(net "FM_SWB_PWR_EN_R1_BUF")
		)
	)
)
